# T6G (Grand Teton) — schematic netlist excerpt (pin names and nets, part order shuffled) for the footprints in the layout excerpt that follows; sources: Cadence DE-HDL packaged netlist, KiCad conversion of 04192023_DAF0TMB3IC0_F0TG_MB_C_brd_V02_OCP.brd

PR6813  Q_RES  1K 1% EMPTY  pkg 0402LF  page 364 : A = P0V9_RETIMER_CPU1_VINSEN ; B = GND
C618  Q_CAP  1UF 4V 20% X6S  pkg 0201  page 290 : A = P0V9_CPU0_RT1_2A ; B = GND
R1431  Q_RES  1K 1% CHIP  pkg 0201LF  page 185 : A = P1V8_CPU0_RT_1D ; B = SMB_RT_CPU0_P2_ROM_MUX_1D_SDA
R6723  Q_RES  200 1% CHIP  pkg 0201LF  page 320 : A = RT_CPU1_P0_SCAN_MODE ; B = GND

(kicad_pcb
	(version 20260206)
	(generator "pcbnew")
	(generator_version "10.0")
	(general
		(thickness 1.6)
		(legacy_teardrops no)
	)
	(paper "A4")
	(title_block
		(title "04192023_DAF0TMB3IC0_F0TG_MB_C_brd_V02_OCP.brd")
		(comment 1 "Grand Teton / footprints 5926-5929 of 8354")
	)
	(layers
		(0 "F.Cu" signal "TOP")
		(4 "In1.Cu" signal "GND")
		(6 "In2.Cu" signal "IN1")
		(8 "In3.Cu" signal "GND1")
		(10 "In4.Cu" signal "IN2")
		(12 "In5.Cu" signal "GND2")
		(14 "In6.Cu" signal "IN3")
		(16 "In7.Cu" signal "GND3")
		(18 "In8.Cu" signal "VCC")
		(20 "In9.Cu" signal "VCC1")
		(22 "In10.Cu" signal "GND4")
		(24 "In11.Cu" signal "IN4")
		(26 "In12.Cu" signal "GND5")
		(28 "In13.Cu" signal "IN5")
		(30 "In14.Cu" signal "GND6")
		(32 "In15.Cu" signal "IN6")
		(34 "In16.Cu" signal "GND7")
		(2 "B.Cu" signal "BOTTOM")
		(9 "F.Adhes" user "F.Adhesive")
		(11 "B.Adhes" user "B.Adhesive")
		(13 "F.Paste" user "Package Geometry/Pastemask Top")
		(15 "B.Paste" user "Package Geometry/Pastemask Bottom")
		(5 "F.SilkS" user "Ref Des/Silkscreen Top")
		(7 "B.SilkS" user "Ref Des/Silkscreen Bottom")
		(1 "F.Mask" user "Board Geometry/Soldermask Top")
		(3 "B.Mask" user "Board Geometry/Soldermask Bottom")
		(17 "Dwgs.User" user "User.Drawings")
		(19 "Cmts.User" user "User.Comments")
		(21 "Eco1.User" user "User.Eco1")
		(23 "Eco2.User" user "User.Eco2")
		(25 "Edge.Cuts" user "Board Geometry/Outline")
		(27 "Margin" user)
		(31 "F.CrtYd" user "Package Geometry/Place Bound Top")
		(29 "B.CrtYd" user "Package Geometry/Place Bound Bottom")
		(35 "F.Fab" user "Ref Des/Assembly Top")
		(33 "B.Fab" user "Ref Des/Assembly Bottom")
	)
	(footprint ""
		(layer "B.Cu")
		(at 10.066782 -407.262584)
		(property "Reference" "PR6813"
			(at 0 0 0)
			(layer "B.SilkS")
			(hide yes)
			(effects
				(font
					(size 1.27 1.27)
				)
				(justify mirror)
			)
		)
		(property "Value" ""
			(at 0 0 0)
			(layer "B.Fab")
			(effects
				(font
					(size 1.27 1.27)
				)
				(justify mirror)
			)
		)
		(duplicate_pad_numbers_are_jumpers no)
		(fp_line
			(start -0.7874 -0.4064)
			(end -0.7874 0.4064)
			(stroke
				(width 0.1524)
				(type default)
			)
			(layer "B.SilkS")
		)
		(fp_line
			(start -0.7874 0.4064)
			(end 0.7874 0.4064)
			(stroke
				(width 0.1524)
				(type default)
			)
			(layer "B.SilkS")
		)
		(fp_line
			(start 0.7874 -0.4064)
			(end -0.7874 -0.4064)
			(stroke
				(width 0.1524)
				(type default)
			)
			(layer "B.SilkS")
		)
		(fp_line
			(start 0.7874 0.4064)
			(end 0.7874 -0.4064)
			(stroke
				(width 0.1524)
				(type default)
			)
			(layer "B.SilkS")
		)
		(fp_line
			(start -0.67945 -0.3048)
			(end -0.67945 0.3048)
			(stroke
				(width 0.1)
				(type default)
			)
			(layer "B.Fab")
		)
		(fp_line
			(start -0.67945 0.3048)
			(end -0.120396 0.3048)
			(stroke
				(width 0.1)
				(type default)
			)
			(layer "B.Fab")
		)
		(fp_line
			(start -0.12065 -0.3048)
			(end -0.67945 -0.3048)
			(stroke
				(width 0.1)
				(type default)
			)
			(layer "B.Fab")
		)
		(fp_line
			(start -0.12065 -0.2794)
			(end -0.12065 -0.3048)
			(stroke
				(width 0.1)
				(type default)
			)
			(layer "B.Fab")
		)
		(fp_line
			(start -0.120396 0.2794)
			(end 0.12065 0.2794)
			(stroke
				(width 0.1)
				(type default)
			)
			(layer "B.Fab")
		)
		(fp_line
			(start -0.120396 0.3048)
			(end -0.120396 0.2794)
			(stroke
				(width 0.1)
				(type default)
			)
			(layer "B.Fab")
		)
		(fp_line
			(start 0.12065 -0.305054)
			(end 0.12065 -0.2794)
			(stroke
				(width 0.1)
				(type default)
			)
			(layer "B.Fab")
		)
		(fp_line
			(start 0.12065 -0.2794)
			(end -0.12065 -0.2794)
			(stroke
				(width 0.1)
				(type default)
			)
			(layer "B.Fab")
		)
		(fp_line
			(start 0.12065 0.2794)
			(end 0.12065 0.3048)
			(stroke
				(width 0.1)
				(type default)
			)
			(layer "B.Fab")
		)
		(fp_line
			(start 0.12065 0.3048)
			(end 0.67945 0.3048)
			(stroke
				(width 0.1)
				(type default)
			)
			(layer "B.Fab")
		)
		(fp_line
			(start 0.67945 -0.305054)
			(end 0.12065 -0.305054)
			(stroke
				(width 0.1)
				(type default)
			)
			(layer "B.Fab")
		)
		(fp_line
			(start 0.67945 0.3048)
			(end 0.67945 -0.305054)
			(stroke
				(width 0.1)
				(type default)
			)
			(layer "B.Fab")
		)
		(pad "1" smd circle
			(at 0.40005 0 180)
			(size 0 0)
			(layers "B.Cu" "B.Mask" "B.Paste")
			(net "P0V9_RETIMER_CPU1_VINSEN")
		)
		(pad "2" smd circle
			(at -0.40005 0 180)
			(size 0 0)
			(layers "B.Cu" "B.Mask" "B.Paste")
			(net "GND")
		)
	)
	(footprint ""
		(layer "B.Cu")
		(at 350.306132 -395.148562 90)
		(property "Reference" "C618"
			(at 0 0 90)
			(layer "B.SilkS")
			(hide yes)
			(effects
				(font
					(size 1.27 1.27)
				)
				(justify mirror)
			)
		)
		(property "Value" ""
			(at 0 0 90)
			(layer "B.Fab")
			(effects
				(font
					(size 1.27 1.27)
				)
				(justify mirror)
			)
		)
		(duplicate_pad_numbers_are_jumpers no)
		(fp_line
			(start 0.299974 -0.150114)
			(end -0.299974 -0.150114)
			(stroke
				(width 0.1)
				(type default)
			)
			(layer "B.Fab")
		)
		(fp_line
			(start -0.299974 -0.150114)
			(end -0.299974 0.150114)
			(stroke
				(width 0.1)
				(type default)
			)
			(layer "B.Fab")
		)
		(fp_line
			(start 0.299974 0.150114)
			(end 0.299974 -0.150114)
			(stroke
				(width 0.1)
				(type default)
			)
			(layer "B.Fab")
		)
		(fp_line
			(start -0.299974 0.150114)
			(end 0.299974 0.150114)
			(stroke
				(width 0.1)
				(type default)
			)
			(layer "B.Fab")
		)
		(pad "1" smd rect
			(at 0.2667 0 270)
			(size 0.3048 0.381)
			(layers "B.Cu" "B.Mask" "B.Paste")
			(net "P0V9_CPU0_RT1_2A")
		)
		(pad "2" smd rect
			(at -0.2667 0 270)
			(size 0.3048 0.381)
			(layers "B.Cu" "B.Mask" "B.Paste")
			(net "GND")
		)
	)
	(footprint ""
		(layer "B.Cu")
		(at 424.684444 -426.718222 -90)
		(property "Reference" "R1431"
			(at 0 0 90)
			(layer "B.SilkS")
			(hide yes)
			(effects
				(font
					(size 1.27 1.27)
				)
				(justify mirror)
			)
		)
		(property "Value" ""
			(at 0 0 90)
			(layer "B.Fab")
			(effects
				(font
					(size 1.27 1.27)
				)
				(justify mirror)
			)
		)
		(duplicate_pad_numbers_are_jumpers no)
		(fp_line
			(start -0.32512 0.175006)
			(end 0.32512 0.175006)
			(stroke
				(width 0.1)
				(type default)
			)
			(layer "B.Fab")
		)
		(fp_line
			(start 0.32512 0.175006)
			(end 0.32512 -0.175006)
			(stroke
				(width 0.1)
				(type default)
			)
			(layer "B.Fab")
		)
		(fp_line
			(start -0.32512 -0.175006)
			(end -0.32512 0.175006)
			(stroke
				(width 0.1)
				(type default)
			)
			(layer "B.Fab")
		)
		(fp_line
			(start 0.32512 -0.175006)
			(end -0.32512 -0.175006)
			(stroke
				(width 0.1)
				(type default)
			)
			(layer "B.Fab")
		)
		(pad "1" smd rect
			(at 0.2667 0 90)
			(size 0.3048 0.381)
			(layers "B.Cu" "B.Mask" "B.Paste")
			(net "P1V8_CPU0_RT_1D")
		)
		(pad "2" smd rect
			(at -0.2667 0 270)
			(size 0.3048 0.381)
			(layers "B.Cu" "B.Mask" "B.Paste")
			(net "SMB_RT_CPU0_P2_ROM_MUX_1D_SDA")
		)
	)
	(footprint ""
		(layer "B.Cu")
		(at 43.265852 -383.49936 180)
		(property "Reference" "R6723"
			(at 0 0 0)
			(layer "B.SilkS")
			(hide yes)
			(effects
				(font
					(size 1.27 1.27)
				)
				(justify mirror)
			)
		)
		(property "Value" ""
			(at 0 0 0)
			(layer "B.Fab")
			(effects
				(font
					(size 1.27 1.27)
				)
				(justify mirror)
			)
		)
		(duplicate_pad_numbers_are_jumpers no)
		(fp_line
			(start 0.32512 0.175006)
			(end 0.32512 -0.175006)
			(stroke
				(width 0.1)
				(type default)
			)
			(layer "B.Fab")
		)
		(fp_line
			(start 0.32512 -0.175006)
			(end -0.32512 -0.175006)
			(stroke
				(width 0.1)
				(type default)
			)
			(layer "B.Fab")
		)
		(fp_line
			(start -0.32512 0.175006)
			(end 0.32512 0.175006)
			(stroke
				(width 0.1)
				(type default)
			)
			(layer "B.Fab")
		)
		(fp_line
			(start -0.32512 -0.175006)
			(end -0.32512 0.175006)
			(stroke
				(width 0.1)
				(type default)
			)
			(layer "B.Fab")
		)
		(pad "1" smd rect
			(at 0.2667 0)
			(size 0.3048 0.381)
			(layers "B.Cu" "B.Mask" "B.Paste")
			(net "RT_CPU1_P0_SCAN_MODE")
		)
		(pad "2" smd rect
			(at -0.2667 0 180)
			(size 0.3048 0.381)
			(layers "B.Cu" "B.Mask" "B.Paste")
			(net "GND")
		)
	)
)
